# T6G (Grand Teton) — schematic netlist excerpt (pin names and nets, part order shuffled) for the footprints in the layout excerpt that follows; sources: Cadence DE-HDL packaged netlist, KiCad conversion of 04192023_DAF0TMB3IC0_F0TG_MB_C_brd_V02_OCP.brd

R314  Q_RES  1K 1% CHIP  pkg 0402LF  page 109 : A = PWRGD_CHL_CPU1_DIMM ; B = PWRGD_CHGL_CPU1
C8000  Q_CAP  1000PF 50V 5% EMPTY  pkg 0402  page 123 : A = PRSNT_SWB_ISO_N ; B = GND

(kicad_pcb
	(version 20260206)
	(generator "pcbnew")
	(generator_version "10.0")
	(general
		(thickness 1.6)
		(legacy_teardrops no)
	)
	(paper "A4")
	(title_block
		(title "04192023_DAF0TMB3IC0_F0TG_MB_C_brd_V02_OCP.brd")
		(comment 1 "Grand Teton / footprints 7530-7531 of 8354")
	)
	(layers
		(0 "F.Cu" signal "TOP")
		(4 "In1.Cu" signal "GND")
		(6 "In2.Cu" signal "IN1")
		(8 "In3.Cu" signal "GND1")
		(10 "In4.Cu" signal "IN2")
		(12 "In5.Cu" signal "GND2")
		(14 "In6.Cu" signal "IN3")
		(16 "In7.Cu" signal "GND3")
		(18 "In8.Cu" signal "VCC")
		(20 "In9.Cu" signal "VCC1")
		(22 "In10.Cu" signal "GND4")
		(24 "In11.Cu" signal "IN4")
		(26 "In12.Cu" signal "GND5")
		(28 "In13.Cu" signal "IN5")
		(30 "In14.Cu" signal "GND6")
		(32 "In15.Cu" signal "IN6")
		(34 "In16.Cu" signal "GND7")
		(2 "B.Cu" signal "BOTTOM")
		(9 "F.Adhes" user "F.Adhesive")
		(11 "B.Adhes" user "B.Adhesive")
		(13 "F.Paste" user "Package Geometry/Pastemask Top")
		(15 "B.Paste" user "Package Geometry/Pastemask Bottom")
		(5 "F.SilkS" user "Ref Des/Silkscreen Top")
		(7 "B.SilkS" user "Ref Des/Silkscreen Bottom")
		(1 "F.Mask" user "Board Geometry/Soldermask Top")
		(3 "B.Mask" user "Board Geometry/Soldermask Bottom")
		(17 "Dwgs.User" user "User.Drawings")
		(19 "Cmts.User" user "User.Comments")
		(21 "Eco1.User" user "User.Eco1")
		(23 "Eco2.User" user "User.Eco2")
		(25 "Edge.Cuts" user "Board Geometry/Outline")
		(27 "Margin" user)
		(31 "F.CrtYd" user "Package Geometry/Place Bound Top")
		(29 "B.CrtYd" user "Package Geometry/Place Bound Bottom")
		(35 "F.Fab" user "Ref Des/Assembly Top")
		(33 "B.Fab" user "Ref Des/Assembly Bottom")
	)
	(footprint ""
		(layer "B.Cu")
		(at 202.15733 -190.94831 180)
		(property "Reference" "R314"
			(at 0 0 0)
			(layer "B.SilkS")
			(hide yes)
			(effects
				(font
					(size 1.27 1.27)
				)
				(justify mirror)
			)
		)
		(property "Value" ""
			(at 0 0 0)
			(layer "B.Fab")
			(effects
				(font
					(size 1.27 1.27)
				)
				(justify mirror)
			)
		)
		(duplicate_pad_numbers_are_jumpers no)
		(fp_line
			(start 0.7874 0.4064)
			(end 0.7874 -0.4064)
			(stroke
				(width 0.1524)
				(type default)
			)
			(layer "B.SilkS")
		)
		(fp_line
			(start 0.7874 -0.4064)
			(end -0.7874 -0.4064)
			(stroke
				(width 0.1524)
				(type default)
			)
			(layer "B.SilkS")
		)
		(fp_line
			(start -0.7874 0.4064)
			(end 0.7874 0.4064)
			(stroke
				(width 0.1524)
				(type default)
			)
			(layer "B.SilkS")
		)
		(fp_line
			(start -0.7874 -0.4064)
			(end -0.7874 0.4064)
			(stroke
				(width 0.1524)
				(type default)
			)
			(layer "B.SilkS")
		)
		(fp_line
			(start 0.67945 0.3048)
			(end 0.67945 -0.305054)
			(stroke
				(width 0.1)
				(type default)
			)
			(layer "B.Fab")
		)
		(fp_line
			(start 0.67945 -0.305054)
			(end 0.12065 -0.305054)
			(stroke
				(width 0.1)
				(type default)
			)
			(layer "B.Fab")
		)
		(fp_line
			(start 0.12065 0.3048)
			(end 0.67945 0.3048)
			(stroke
				(width 0.1)
				(type default)
			)
			(layer "B.Fab")
		)
		(fp_line
			(start 0.12065 0.2794)
			(end 0.12065 0.3048)
			(stroke
				(width 0.1)
				(type default)
			)
			(layer "B.Fab")
		)
		(fp_line
			(start 0.12065 -0.2794)
			(end -0.12065 -0.2794)
			(stroke
				(width 0.1)
				(type default)
			)
			(layer "B.Fab")
		)
		(fp_line
			(start 0.12065 -0.305054)
			(end 0.12065 -0.2794)
			(stroke
				(width 0.1)
				(type default)
			)
			(layer "B.Fab")
		)
		(fp_line
			(start -0.120396 0.3048)
			(end -0.120396 0.2794)
			(stroke
				(width 0.1)
				(type default)
			)
			(layer "B.Fab")
		)
		(fp_line
			(start -0.120396 0.2794)
			(end 0.12065 0.2794)
			(stroke
				(width 0.1)
				(type default)
			)
			(layer "B.Fab")
		)
		(fp_line
			(start -0.12065 -0.2794)
			(end -0.12065 -0.3048)
			(stroke
				(width 0.1)
				(type default)
			)
			(layer "B.Fab")
		)
		(fp_line
			(start -0.12065 -0.3048)
			(end -0.67945 -0.3048)
			(stroke
				(width 0.1)
				(type default)
			)
			(layer "B.Fab")
		)
		(fp_line
			(start -0.67945 0.3048)
			(end -0.120396 0.3048)
			(stroke
				(width 0.1)
				(type default)
			)
			(layer "B.Fab")
		)
		(fp_line
			(start -0.67945 -0.3048)
			(end -0.67945 0.3048)
			(stroke
				(width 0.1)
				(type default)
			)
			(layer "B.Fab")
		)
		(pad "1" smd circle
			(at 0.40005 0)
			(size 0 0)
			(layers "B.Cu" "B.Mask" "B.Paste")
			(net "PWRGD_CHL_CPU1_DIMM")
		)
		(pad "2" smd circle
			(at -0.40005 0)
			(size 0 0)
			(layers "B.Cu" "B.Mask" "B.Paste")
			(net "PWRGD_CHGL_CPU1")
		)
	)
	(footprint ""
		(layer "B.Cu")
		(at 97.591118 -425.19219)
		(property "Reference" "C8000"
			(at 0 0 0)
			(layer "B.SilkS")
			(hide yes)
			(effects
				(font
					(size 1.27 1.27)
				)
				(justify mirror)
			)
		)
		(property "Value" ""
			(at 0 0 0)
			(layer "B.Fab")
			(effects
				(font
					(size 1.27 1.27)
				)
				(justify mirror)
			)
		)
		(duplicate_pad_numbers_are_jumpers no)
		(fp_line
			(start -0.7874 -0.4064)
			(end -0.7874 0.4064)
			(stroke
				(width 0.1524)
				(type default)
			)
			(layer "B.SilkS")
		)
		(fp_line
			(start -0.7874 0.4064)
			(end 0.7874 0.4064)
			(stroke
				(width 0.1524)
				(type default)
			)
			(layer "B.SilkS")
		)
		(fp_line
			(start 0.7874 -0.4064)
			(end -0.7874 -0.4064)
			(stroke
				(width 0.1524)
				(type default)
			)
			(layer "B.SilkS")
		)
		(fp_line
			(start 0.7874 0.4064)
			(end 0.7874 -0.4064)
			(stroke
				(width 0.1524)
				(type default)
			)
			(layer "B.SilkS")
		)
		(fp_line
			(start -0.67945 -0.3048)
			(end -0.67945 0.3048)
			(stroke
				(width 0.1)
				(type default)
			)
			(layer "B.Fab")
		)
		(fp_line
			(start -0.67945 0.3048)
			(end -0.120396 0.3048)
			(stroke
				(width 0.1)
				(type default)
			)
			(layer "B.Fab")
		)
		(fp_line
			(start -0.12065 -0.3048)
			(end -0.67945 -0.3048)
			(stroke
				(width 0.1)
				(type default)
			)
			(layer "B.Fab")
		)
		(fp_line
			(start -0.12065 -0.2794)
			(end -0.12065 -0.3048)
			(stroke
				(width 0.1)
				(type default)
			)
			(layer "B.Fab")
		)
		(fp_line
			(start -0.120396 0.2794)
			(end 0.12065 0.2794)
			(stroke
				(width 0.1)
				(type default)
			)
			(layer "B.Fab")
		)
		(fp_line
			(start -0.120396 0.3048)
			(end -0.120396 0.2794)
			(stroke
				(width 0.1)
				(type default)
			)
			(layer "B.Fab")
		)
		(fp_line
			(start 0.12065 -0.305054)
			(end 0.12065 -0.2794)
			(stroke
				(width 0.1)
				(type default)
			)
			(layer "B.Fab")
		)
		(fp_line
			(start 0.12065 -0.2794)
			(end -0.12065 -0.2794)
			(stroke
				(width 0.1)
				(type default)
			)
			(layer "B.Fab")
		)
		(fp_line
			(start 0.12065 0.2794)
			(end 0.12065 0.3048)
			(stroke
				(width 0.1)
				(type default)
			)
			(layer "B.Fab")
		)
		(fp_line
			(start 0.12065 0.3048)
			(end 0.67945 0.3048)
			(stroke
				(width 0.1)
				(type default)
			)
			(layer "B.Fab")
		)
		(fp_line
			(start 0.67945 -0.305054)
			(end 0.12065 -0.305054)
			(stroke
				(width 0.1)
				(type default)
			)
			(layer "B.Fab")
		)
		(fp_line
			(start 0.67945 0.3048)
			(end 0.67945 -0.305054)
			(stroke
				(width 0.1)
				(type default)
			)
			(layer "B.Fab")
		)
		(pad "1" smd circle
			(at 0.40005 0 180)
			(size 0 0)
			(layers "B.Cu" "B.Mask" "B.Paste")
			(net "PRSNT_SWB_ISO_N")
		)
		(pad "2" smd circle
			(at -0.40005 0 180)
			(size 0 0)
			(layers "B.Cu" "B.Mask" "B.Paste")
			(net "GND")
		)
	)
)
